# T6G (Grand Teton) — schematic netlist excerpt (pin names and nets, part order shuffled) for the footprints in the layout excerpt that follows; sources: Cadence DE-HDL packaged netlist, KiCad conversion of 04192023_DAF0TMB3IC0_F0TG_MB_C_brd_V02_OCP.brd

R1582  Q_RES  49.9 1% CHIP  pkg 0402LF  page 100 : A = I3C_SPD_DDRAF_CPU1_SCL ; B = I3C_SPD_DDRC_CPU1_SCL
R455  Q_RES  4.7K 5% EMPTY  pkg 0402LF  page 29 : A = PVDD18_S5_P0 ; B = ESPI_CPU0_CS1_N

(kicad_pcb
	(version 20260206)
	(generator "pcbnew")
	(generator_version "10.0")
	(general
		(thickness 1.6)
		(legacy_teardrops no)
	)
	(paper "A4")
	(title_block
		(title "04192023_DAF0TMB3IC0_F0TG_MB_C_brd_V02_OCP.brd")
		(comment 1 "Grand Teton / footprints 6177-6178 of 8354")
	)
	(layers
		(0 "F.Cu" signal "TOP")
		(4 "In1.Cu" signal "GND")
		(6 "In2.Cu" signal "IN1")
		(8 "In3.Cu" signal "GND1")
		(10 "In4.Cu" signal "IN2")
		(12 "In5.Cu" signal "GND2")
		(14 "In6.Cu" signal "IN3")
		(16 "In7.Cu" signal "GND3")
		(18 "In8.Cu" signal "VCC")
		(20 "In9.Cu" signal "VCC1")
		(22 "In10.Cu" signal "GND4")
		(24 "In11.Cu" signal "IN4")
		(26 "In12.Cu" signal "GND5")
		(28 "In13.Cu" signal "IN5")
		(30 "In14.Cu" signal "GND6")
		(32 "In15.Cu" signal "IN6")
		(34 "In16.Cu" signal "GND7")
		(2 "B.Cu" signal "BOTTOM")
		(9 "F.Adhes" user "F.Adhesive")
		(11 "B.Adhes" user "B.Adhesive")
		(13 "F.Paste" user "Package Geometry/Pastemask Top")
		(15 "B.Paste" user "Package Geometry/Pastemask Bottom")
		(5 "F.SilkS" user "Ref Des/Silkscreen Top")
		(7 "B.SilkS" user "Ref Des/Silkscreen Bottom")
		(1 "F.Mask" user "Board Geometry/Soldermask Top")
		(3 "B.Mask" user "Board Geometry/Soldermask Bottom")
		(17 "Dwgs.User" user "User.Drawings")
		(19 "Cmts.User" user "User.Comments")
		(21 "Eco1.User" user "User.Eco1")
		(23 "Eco2.User" user "User.Eco2")
		(25 "Edge.Cuts" user "Board Geometry/Outline")
		(27 "Margin" user)
		(31 "F.CrtYd" user "Package Geometry/Place Bound Top")
		(29 "B.CrtYd" user "Package Geometry/Place Bound Bottom")
		(35 "F.Fab" user "Ref Des/Assembly Top")
		(33 "B.Fab" user "Ref Des/Assembly Bottom")
	)
	(footprint ""
		(layer "B.Cu")
		(at 43.576748 -194.987164 180)
		(property "Reference" "R1582"
			(at 0 0 0)
			(layer "B.SilkS")
			(hide yes)
			(effects
				(font
					(size 1.27 1.27)
				)
				(justify mirror)
			)
		)
		(property "Value" ""
			(at 0 0 0)
			(layer "B.Fab")
			(effects
				(font
					(size 1.27 1.27)
				)
				(justify mirror)
			)
		)
		(duplicate_pad_numbers_are_jumpers no)
		(fp_line
			(start 0.7874 0.4064)
			(end 0.7874 -0.4064)
			(stroke
				(width 0.1524)
				(type default)
			)
			(layer "B.SilkS")
		)
		(fp_line
			(start 0.7874 -0.4064)
			(end -0.7874 -0.4064)
			(stroke
				(width 0.1524)
				(type default)
			)
			(layer "B.SilkS")
		)
		(fp_line
			(start -0.7874 0.4064)
			(end 0.7874 0.4064)
			(stroke
				(width 0.1524)
				(type default)
			)
			(layer "B.SilkS")
		)
		(fp_line
			(start -0.7874 -0.4064)
			(end -0.7874 0.4064)
			(stroke
				(width 0.1524)
				(type default)
			)
			(layer "B.SilkS")
		)
		(fp_line
			(start 0.67945 0.3048)
			(end 0.67945 -0.305054)
			(stroke
				(width 0.1)
				(type default)
			)
			(layer "B.Fab")
		)
		(fp_line
			(start 0.67945 -0.305054)
			(end 0.12065 -0.305054)
			(stroke
				(width 0.1)
				(type default)
			)
			(layer "B.Fab")
		)
		(fp_line
			(start 0.12065 0.3048)
			(end 0.67945 0.3048)
			(stroke
				(width 0.1)
				(type default)
			)
			(layer "B.Fab")
		)
		(fp_line
			(start 0.12065 0.2794)
			(end 0.12065 0.3048)
			(stroke
				(width 0.1)
				(type default)
			)
			(layer "B.Fab")
		)
		(fp_line
			(start 0.12065 -0.2794)
			(end -0.12065 -0.2794)
			(stroke
				(width 0.1)
				(type default)
			)
			(layer "B.Fab")
		)
		(fp_line
			(start 0.12065 -0.305054)
			(end 0.12065 -0.2794)
			(stroke
				(width 0.1)
				(type default)
			)
			(layer "B.Fab")
		)
		(fp_line
			(start -0.120396 0.3048)
			(end -0.120396 0.2794)
			(stroke
				(width 0.1)
				(type default)
			)
			(layer "B.Fab")
		)
		(fp_line
			(start -0.120396 0.2794)
			(end 0.12065 0.2794)
			(stroke
				(width 0.1)
				(type default)
			)
			(layer "B.Fab")
		)
		(fp_line
			(start -0.12065 -0.2794)
			(end -0.12065 -0.3048)
			(stroke
				(width 0.1)
				(type default)
			)
			(layer "B.Fab")
		)
		(fp_line
			(start -0.12065 -0.3048)
			(end -0.67945 -0.3048)
			(stroke
				(width 0.1)
				(type default)
			)
			(layer "B.Fab")
		)
		(fp_line
			(start -0.67945 0.3048)
			(end -0.120396 0.3048)
			(stroke
				(width 0.1)
				(type default)
			)
			(layer "B.Fab")
		)
		(fp_line
			(start -0.67945 -0.3048)
			(end -0.67945 0.3048)
			(stroke
				(width 0.1)
				(type default)
			)
			(layer "B.Fab")
		)
		(pad "1" smd circle
			(at 0.40005 0)
			(size 0 0)
			(layers "B.Cu" "B.Mask" "B.Paste")
			(net "I3C_SPD_DDRAF_CPU1_SCL")
		)
		(pad "2" smd circle
			(at -0.40005 0)
			(size 0 0)
			(layers "B.Cu" "B.Mask" "B.Paste")
			(net "I3C_SPD_DDRC_CPU1_SCL")
		)
	)
	(footprint ""
		(layer "B.Cu")
		(at 406.698958 -324.862952)
		(property "Reference" "R455"
			(at 0 0 0)
			(layer "B.SilkS")
			(hide yes)
			(effects
				(font
					(size 1.27 1.27)
				)
				(justify mirror)
			)
		)
		(property "Value" ""
			(at 0 0 0)
			(layer "B.Fab")
			(effects
				(font
					(size 1.27 1.27)
				)
				(justify mirror)
			)
		)
		(duplicate_pad_numbers_are_jumpers no)
		(fp_line
			(start -0.7874 -0.4064)
			(end -0.7874 0.4064)
			(stroke
				(width 0.1524)
				(type default)
			)
			(layer "B.SilkS")
		)
		(fp_line
			(start -0.7874 0.4064)
			(end 0.7874 0.4064)
			(stroke
				(width 0.1524)
				(type default)
			)
			(layer "B.SilkS")
		)
		(fp_line
			(start 0.7874 -0.4064)
			(end -0.7874 -0.4064)
			(stroke
				(width 0.1524)
				(type default)
			)
			(layer "B.SilkS")
		)
		(fp_line
			(start 0.7874 0.4064)
			(end 0.7874 -0.4064)
			(stroke
				(width 0.1524)
				(type default)
			)
			(layer "B.SilkS")
		)
		(fp_line
			(start -0.67945 -0.3048)
			(end -0.67945 0.3048)
			(stroke
				(width 0.1)
				(type default)
			)
			(layer "B.Fab")
		)
		(fp_line
			(start -0.67945 0.3048)
			(end -0.120396 0.3048)
			(stroke
				(width 0.1)
				(type default)
			)
			(layer "B.Fab")
		)
		(fp_line
			(start -0.12065 -0.3048)
			(end -0.67945 -0.3048)
			(stroke
				(width 0.1)
				(type default)
			)
			(layer "B.Fab")
		)
		(fp_line
			(start -0.12065 -0.2794)
			(end -0.12065 -0.3048)
			(stroke
				(width 0.1)
				(type default)
			)
			(layer "B.Fab")
		)
		(fp_line
			(start -0.120396 0.2794)
			(end 0.12065 0.2794)
			(stroke
				(width 0.1)
				(type default)
			)
			(layer "B.Fab")
		)
		(fp_line
			(start -0.120396 0.3048)
			(end -0.120396 0.2794)
			(stroke
				(width 0.1)
				(type default)
			)
			(layer "B.Fab")
		)
		(fp_line
			(start 0.12065 -0.305054)
			(end 0.12065 -0.2794)
			(stroke
				(width 0.1)
				(type default)
			)
			(layer "B.Fab")
		)
		(fp_line
			(start 0.12065 -0.2794)
			(end -0.12065 -0.2794)
			(stroke
				(width 0.1)
				(type default)
			)
			(layer "B.Fab")
		)
		(fp_line
			(start 0.12065 0.2794)
			(end 0.12065 0.3048)
			(stroke
				(width 0.1)
				(type default)
			)
			(layer "B.Fab")
		)
		(fp_line
			(start 0.12065 0.3048)
			(end 0.67945 0.3048)
			(stroke
				(width 0.1)
				(type default)
			)
			(layer "B.Fab")
		)
		(fp_line
			(start 0.67945 -0.305054)
			(end 0.12065 -0.305054)
			(stroke
				(width 0.1)
				(type default)
			)
			(layer "B.Fab")
		)
		(fp_line
			(start 0.67945 0.3048)
			(end 0.67945 -0.305054)
			(stroke
				(width 0.1)
				(type default)
			)
			(layer "B.Fab")
		)
		(pad "1" smd circle
			(at 0.40005 0 180)
			(size 0 0)
			(layers "B.Cu" "B.Mask" "B.Paste")
			(net "PVDD18_S5_P0")
		)
		(pad "2" smd circle
			(at -0.40005 0 180)
			(size 0 0)
			(layers "B.Cu" "B.Mask" "B.Paste")
			(net "ESPI_CPU0_CS1_N")
		)
	)
)
